(kicad_pcb
	(version 20241229)
	(generator "pcbnew")
	(generator_version "9.0")
	(general
		(thickness 1.552)
		(legacy_teardrops no)
	)
	(paper "A4")
	(title_block
		(date "2023-07-25")
		(rev "1.1.4")
		(comment 9 "footprints 29-33 of 379")
	)
	(layers
		(0 "F.Cu" signal)
		(4 "In1.Cu" signal)
		(6 "In2.Cu" signal)
		(8 "In3.Cu" signal)
		(10 "In4.Cu" signal)
		(12 "In5.Cu" signal)
		(14 "In6.Cu" signal)
		(2 "B.Cu" signal)
		(9 "F.Adhes" user "F.Adhesive")
		(11 "B.Adhes" user "B.Adhesive")
		(13 "F.Paste" user)
		(15 "B.Paste" user)
		(5 "F.SilkS" user "F.Silkscreen")
		(7 "B.SilkS" user "B.Silkscreen")
		(1 "F.Mask" user)
		(3 "B.Mask" user)
		(17 "Dwgs.User" user "User.Drawings")
		(19 "Cmts.User" user "User.Comments")
		(21 "Eco1.User" user "User.Eco1")
		(23 "Eco2.User" user "User.Eco2")
		(25 "Edge.Cuts" user)
		(27 "Margin" user)
		(31 "F.CrtYd" user "F.Courtyard")
		(29 "B.CrtYd" user "B.Courtyard")
		(35 "F.Fab" user)
		(33 "B.Fab" user)
	)
	(footprint "antmicro-footprints:C_0402_1005Metric"
		(layer "F.Cu")
		(at 161.915 84.15 180)
		(descr "Capacitor SMD 0402")
		(tags "capacitor SMD 0402")
		(property "Reference" "C110"
			(at 1.885 -0.39 0)
			(layer "F.SilkS")
			(effects
				(font
					(size 0.65 0.65)
					(thickness 0.15)
				)
				(justify right bottom)
			)
		)
		(property "Value" "C_100n_0402"
			(at 0 1.4 0)
			(layer "F.Fab")
			(hide yes)
			(effects
				(font
					(size 0.7 0.7)
					(thickness 0.15)
				)
				(justify right bottom)
			)
		)
		(property "Datasheet" "https://www.murata.com/products/productdetail?partno=GRM155R61H104KE14%23"
			(at 0 0 180)
			(layer "F.Fab")
			(hide yes)
			(effects
				(font
					(size 1.27 1.27)
					(thickness 0.15)
				)
			)
		)
		(property "Description" "SMD Multilayer Ceramic Capacitor, 0.1 µF, 50 V, 0402 [1005 Metric], ± 10%, X5R, GRM Series"
			(at 0 0 180)
			(layer "F.Fab")
			(hide yes)
			(effects
				(font
					(size 1.27 1.27)
					(thickness 0.15)
				)
			)
		)
		(property "Author" "Antmicro"
			(at 323.83 168.3 0)
			(layer "F.Fab")
			(hide yes)
			(effects
				(font
					(size 1 1)
					(thickness 0.15)
				)
			)
		)
		(property "Dielectric" "X5R"
			(at 323.83 168.3 0)
			(layer "F.Fab")
			(hide yes)
			(effects
				(font
					(size 1 1)
					(thickness 0.15)
				)
			)
		)
		(property "License" "Apache-2.0"
			(at 323.83 168.3 0)
			(layer "F.Fab")
			(hide yes)
			(effects
				(font
					(size 1 1)
					(thickness 0.15)
				)
			)
		)
		(property "MPN" "GRM155R61H104KE14D"
			(at 323.83 168.3 0)
			(layer "F.Fab")
			(hide yes)
			(effects
				(font
					(size 1 1)
					(thickness 0.15)
				)
			)
		)
		(property "Manufacturer" "Murata"
			(at 323.83 168.3 0)
			(layer "F.Fab")
			(hide yes)
			(effects
				(font
					(size 1 1)
					(thickness 0.15)
				)
			)
		)
		(property "Val" "100n"
			(at 323.83 168.3 0)
			(layer "F.Fab")
			(hide yes)
			(effects
				(font
					(size 1 1)
					(thickness 0.15)
				)
			)
		)
		(property "Voltage" "50V"
			(at 323.83 168.3 0)
			(layer "F.Fab")
			(hide yes)
			(effects
				(font
					(size 1 1)
					(thickness 0.15)
				)
			)
		)
		(sheetname "/Peripherals/")
		(sheetfile "peripherals.kicad_sch")
		(attr smd)
		(fp_rect
			(start -0.925 -0.47)
			(end 0.925 0.47)
			(stroke
				(width 0.05)
				(type default)
			)
			(fill no)
			(layer "F.CrtYd")
		)
		(fp_line
			(start 0.504 0.248)
			(end -0.494 0.248)
			(stroke
				(width 0.15)
				(type solid)
			)
			(layer "F.Fab")
		)
		(fp_line
			(start 0.504 -0.25)
			(end 0.504 0.248)
			(stroke
				(width 0.15)
				(type solid)
			)
			(layer "F.Fab")
		)
		(fp_line
			(start -0.494 0.248)
			(end -0.494 -0.25)
			(stroke
				(width 0.15)
				(type solid)
			)
			(layer "F.Fab")
		)
		(fp_line
			(start -0.494 -0.25)
			(end 0.504 -0.25)
			(stroke
				(width 0.15)
				(type solid)
			)
			(layer "F.Fab")
		)
		(fp_text user "Author: Antmicro"
			(at -0.939 3.399 180)
			(layer "F.Fab")
			(effects
				(font
					(size 0.7 0.7)
					(thickness 0.15)
				)
				(justify left bottom)
			)
		)
		(fp_text user "License: Apache-2.0"
			(at -0.939 5.799 180)
			(layer "F.Fab")
			(effects
				(font
					(size 0.7 0.7)
					(thickness 0.15)
				)
				(justify left bottom)
			)
		)
		(fp_text user "${REFERENCE}"
			(at -0.939 4.599 180)
			(layer "F.Fab")
			(effects
				(font
					(size 0.7 0.7)
					(thickness 0.15)
				)
				(justify left bottom)
			)
		)
		(pad "1" smd roundrect
			(at -0.48 0 180)
			(size 0.59 0.64)
			(layers "F.Cu" "F.Mask" "F.Paste")
			(roundrect_rratio 0.25)
			(net 1 "GND")
			(pintype "passive")
		)
		(pad "2" smd roundrect
			(at 0.48 0 180)
			(size 0.59 0.64)
			(layers "F.Cu" "F.Mask" "F.Paste")
			(roundrect_rratio 0.25)
			(net 14 "+5V")
			(pintype "passive")
		)
	)
	(footprint "antmicro-footprints:R_0603_1608Metric"
		(layer "F.Cu")
		(at 158.29 76.6)
		(descr "Resistor SMD 0603")
		(tags "resistor SMD 0603")
		(property "Reference" "R117"
			(at -4.06 0.54 0)
			(layer "F.SilkS")
			(effects
				(font
					(size 0.65 0.65)
					(thickness 0.15)
				)
				(justify left bottom)
			)
		)
		(property "Value" "R_0R_0603"
			(at 0 1.6 0)
			(layer "F.Fab")
			(hide yes)
			(effects
				(font
					(size 0.7 0.7)
					(thickness 0.15)
				)
				(justify left bottom)
			)
		)
		(property "Datasheet" "https://www.bourns.com/docs/product-datasheets/cr.pdf?sfvrsn=574d41f6_14"
			(at 0 0 0)
			(layer "F.Fab")
			(hide yes)
			(effects
				(font
					(size 1.27 1.27)
					(thickness 0.15)
				)
			)
		)
		(property "Description" "Zero Ohm Resistor, Jumper, 0603 [1608 Metric], Thick Film, 100 mW, 1 A, Surface Mount Device, CR"
			(at 0 0 0)
			(layer "F.Fab")
			(hide yes)
			(effects
				(font
					(size 1.27 1.27)
					(thickness 0.15)
				)
			)
		)
		(property "Author" "Antmicro"
			(at 0 0 0)
			(layer "F.Fab")
			(hide yes)
			(effects
				(font
					(size 1 1)
					(thickness 0.15)
				)
			)
		)
		(property "Current" "1A"
			(at 0 0 0)
			(layer "F.Fab")
			(hide yes)
			(effects
				(font
					(size 1 1)
					(thickness 0.15)
				)
			)
		)
		(property "License" "Apache-2.0"
			(at 0 0 0)
			(layer "F.Fab")
			(hide yes)
			(effects
				(font
					(size 1 1)
					(thickness 0.15)
				)
			)
		)
		(property "MPN" "CR0603-J/-000ELF"
			(at 0 0 0)
			(layer "F.Fab")
			(hide yes)
			(effects
				(font
					(size 1 1)
					(thickness 0.15)
				)
			)
		)
		(property "Manufacturer" "Bourns"
			(at 0 0 0)
			(layer "F.Fab")
			(hide yes)
			(effects
				(font
					(size 1 1)
					(thickness 0.15)
				)
			)
		)
		(property "Tolerance" "~"
			(at 0 0 0)
			(layer "F.Fab")
			(hide yes)
			(effects
				(font
					(size 1 1)
					(thickness 0.15)
				)
			)
		)
		(property "Val" "0R"
			(at 0 0 0)
			(layer "F.Fab")
			(hide yes)
			(effects
				(font
					(size 1 1)
					(thickness 0.15)
				)
			)
		)
		(sheetname "/Peripherals/")
		(sheetfile "peripherals.kicad_sch")
		(attr smd)
		(fp_line
			(start -0.15 -0.4)
			(end 0.15 -0.4)
			(stroke
				(width 0.15)
				(type solid)
			)
			(layer "F.SilkS")
		)
		(fp_line
			(start -0.15 0.4)
			(end 0.15 0.4)
			(stroke
				(width 0.15)
				(type solid)
			)
			(layer "F.SilkS")
		)
		(fp_rect
			(start -1.25 -0.65)
			(end 1.25 0.65)
			(stroke
				(width 0.05)
				(type solid)
			)
			(fill no)
			(layer "F.CrtYd")
		)
		(fp_rect
			(start -0.8 -0.4)
			(end 0.8 0.4)
			(stroke
				(width 0.15)
				(type solid)
			)
			(fill no)
			(layer "F.Fab")
		)
		(fp_text user "Author: Antmicro"
			(at -1.25 4.9 0)
			(layer "F.Fab")
			(effects
				(font
					(size 0.7 0.7)
					(thickness 0.15)
				)
				(justify left bottom)
			)
		)
		(fp_text user "License: Apache-2.0"
			(at -1.25 5.9 0)
			(layer "F.Fab")
			(effects
				(font
					(size 0.7 0.7)
					(thickness 0.15)
				)
				(justify left bottom)
			)
		)
		(fp_text user "${REFERENCE}"
			(at -1.25 3.898 0)
			(layer "F.Fab")
			(effects
				(font
					(size 0.7 0.7)
					(thickness 0.15)
				)
				(justify left bottom)
			)
		)
		(pad "1" smd roundrect
			(at -0.7 0)
			(size 0.8 1)
			(layers "F.Cu" "F.Mask" "F.Paste")
			(roundrect_rratio 0.2)
			(net 100 "SCL")
			(pintype "passive")
		)
		(pad "2" smd roundrect
			(at 0.7 0)
			(size 0.8 1)
			(layers "F.Cu" "F.Mask" "F.Paste")
			(roundrect_rratio 0.2)
			(net 313 "Net-(J8-Pad4)")
			(pintype "passive")
		)
	)
	(footprint "antmicro-footprints:C_0603_1608Metric"
		(layer "F.Cu")
		(at 161.69 76.6 180)
		(descr "Capacitor SMD 0603")
		(tags "capacitor 0603")
		(property "Reference" "C114"
			(at -1.34 0.76 0)
			(layer "F.SilkS")
			(effects
				(font
					(size 0.65 0.65)
					(thickness 0.15)
				)
				(justify right bottom)
			)
		)
		(property "Value" "C_1u_0603"
			(at 0 1.6 0)
			(layer "F.Fab")
			(hide yes)
			(effects
				(font
					(size 0.7 0.7)
					(thickness 0.15)
				)
				(justify right bottom)
			)
		)
		(property "Datasheet" "https://spicat.kyocera-avx.com/product/mlcc/chartview/0603YD105KAT2A/"
			(at 0 0 180)
			(layer "F.Fab")
			(hide yes)
			(effects
				(font
					(size 1.27 1.27)
					(thickness 0.15)
				)
			)
		)
		(property "Description" "SMD Multilayer Ceramic Capacitor, 1 µF, 16 V, 0603 [1608 Metric], ± 10%, X5R, AVX 0603 MLCC"
			(at 0 0 180)
			(layer "F.Fab")
			(hide yes)
			(effects
				(font
					(size 1.27 1.27)
					(thickness 0.15)
				)
			)
		)
		(property "Author" "Antmicro"
			(at 323.38 153.2 0)
			(layer "F.Fab")
			(hide yes)
			(effects
				(font
					(size 1 1)
					(thickness 0.15)
				)
			)
		)
		(property "Dielectric" ""
			(at 323.38 153.2 0)
			(layer "F.Fab")
			(hide yes)
			(effects
				(font
					(size 1 1)
					(thickness 0.15)
				)
			)
		)
		(property "License" "Apache-2.0"
			(at 323.38 153.2 0)
			(layer "F.Fab")
			(hide yes)
			(effects
				(font
					(size 1 1)
					(thickness 0.15)
				)
			)
		)
		(property "MPN" "0603YD105KAT2A"
			(at 323.38 153.2 0)
			(layer "F.Fab")
			(hide yes)
			(effects
				(font
					(size 1 1)
					(thickness 0.15)
				)
			)
		)
		(property "Manufacturer" "KYOCERA AVX"
			(at 323.38 153.2 0)
			(layer "F.Fab")
			(hide yes)
			(effects
				(font
					(size 1 1)
					(thickness 0.15)
				)
			)
		)
		(property "Val" "1u"
			(at 323.38 153.2 0)
			(layer "F.Fab")
			(hide yes)
			(effects
				(font
					(size 1 1)
					(thickness 0.15)
				)
			)
		)
		(property "Voltage" ""
			(at 323.38 153.2 0)
			(layer "F.Fab")
			(hide yes)
			(effects
				(font
					(size 1 1)
					(thickness 0.15)
				)
			)
		)
		(sheetname "/Peripherals/")
		(sheetfile "peripherals.kicad_sch")
		(attr smd)
		(fp_line
			(start -0.15 0.4)
			(end 0.15 0.4)
			(stroke
				(width 0.15)
				(type solid)
			)
			(layer "F.SilkS")
		)
		(fp_line
			(start -0.15 -0.4)
			(end 0.15 -0.4)
			(stroke
				(width 0.15)
				(type solid)
			)
			(layer "F.SilkS")
		)
		(fp_rect
			(start -1.25 -0.65)
			(end 1.25 0.65)
			(stroke
				(width 0.05)
				(type solid)
			)
			(fill no)
			(layer "F.CrtYd")
		)
		(fp_rect
			(start -0.8 -0.4)
			(end 0.8 0.4)
			(stroke
				(width 0.15)
				(type solid)
			)
			(fill no)
			(layer "F.Fab")
		)
		(fp_text user "License: Apache-2.0"
			(at -1.682 5.895 180)
			(layer "F.Fab")
			(effects
				(font
					(size 0.7 0.7)
					(thickness 0.15)
				)
				(justify left bottom)
			)
		)
		(fp_text user "Author: Antmicro"
			(at -1.682 4.894 180)
			(layer "F.Fab")
			(effects
				(font
					(size 0.7 0.7)
					(thickness 0.15)
				)
				(justify left bottom)
			)
		)
		(fp_text user "${REFERENCE}"
			(at -1.682 3.895 180)
			(layer "F.Fab")
			(effects
				(font
					(size 0.7 0.7)
					(thickness 0.15)
				)
				(justify left bottom)
			)
		)
		(pad "1" smd roundrect
			(at -0.7 0 180)
			(size 0.8 1)
			(layers "F.Cu" "F.Mask" "F.Paste")
			(roundrect_rratio 0.2)
			(net 1 "GND")
			(pintype "passive")
		)
		(pad "2" smd roundrect
			(at 0.7 0 180)
			(size 0.8 1)
			(layers "F.Cu" "F.Mask" "F.Paste")
			(roundrect_rratio 0.2)
			(net 310 "/Peripherals/QWIIC_3V3")
			(pintype "passive")
		)
	)
	(footprint "antmicro-footprints:TP_SMD_0.75mm"
		(layer "F.Cu")
		(at 136.39 111.9 90)
		(property "Reference" "TP6"
			(at -1.44 -0.56 90)
			(layer "F.SilkS")
			(effects
				(font
					(size 0.65 0.65)
					(thickness 0.15)
				)
				(justify left bottom)
			)
		)
		(property "Value" "TP_0.75mm_SMD"
			(at 0 1.2 90)
			(layer "F.Fab")
			(hide yes)
			(effects
				(font
					(size 0.7 0.7)
					(thickness 0.15)
				)
				(justify left bottom)
			)
		)
		(property "Description" "SMT test point"
			(at 0 0 90)
			(layer "F.Fab")
			(hide yes)
			(effects
				(font
					(size 1.27 1.27)
					(thickness 0.15)
				)
			)
		)
		(property "Author" "Antmicro"
			(at 248.29 -24.49 0)
			(layer "F.Fab")
			(hide yes)
			(effects
				(font
					(size 1 1)
					(thickness 0.15)
				)
			)
		)
		(property "License" "Apache-2.0"
			(at 248.29 -24.49 0)
			(layer "F.Fab")
			(hide yes)
			(effects
				(font
					(size 1 1)
					(thickness 0.15)
				)
			)
		)
		(property "MPN" ""
			(at 248.29 -24.49 0)
			(layer "F.Fab")
			(hide yes)
			(effects
				(font
					(size 1 1)
					(thickness 0.15)
				)
			)
		)
		(property "Manufacturer" ""
			(at 248.29 -24.49 0)
			(layer "F.Fab")
			(hide yes)
			(effects
				(font
					(size 1 1)
					(thickness 0.15)
				)
			)
		)
		(sheetname "/Power Supply/")
		(sheetfile "supply.kicad_sch")
		(attr exclude_from_pos_files)
		(fp_circle
			(center 0 0)
			(end 0.475 0)
			(stroke
				(width 0.05)
				(type default)
			)
			(fill no)
			(layer "F.CrtYd")
		)
		(fp_text user "${REFERENCE}"
			(at -0.4 2.7 90)
			(layer "F.Fab")
			(effects
				(font
					(size 0.7 0.7)
					(thickness 0.15)
				)
				(justify left bottom)
			)
		)
		(fp_text user "License: Apache-2.0"
			(at -0.4 5.101 90)
			(layer "F.Fab")
			(effects
				(font
					(size 0.7 0.7)
					(thickness 0.15)
				)
				(justify left bottom)
			)
		)
		(fp_text user "Author: Antmicro"
			(at -0.4 3.901 90)
			(layer "F.Fab")
			(effects
				(font
					(size 0.7 0.7)
					(thickness 0.15)
				)
				(justify left bottom)
			)
		)
		(pad "1" smd circle
			(at 0 0 90)
			(size 0.75 0.75)
			(layers "F.Cu" "F.Mask")
			(net 50 "+1V8")
			(pinfunction "1")
			(pintype "passive")
		)
	)
	(footprint "antmicro-footprints:R_0402_1005Metric"
		(layer "F.Cu")
		(at 110.79 102.4)
		(descr "Resistor SMD 0402")
		(tags "resistor SMD 0402")
		(property "Reference" "R85"
			(at 0.94 0.44 0)
			(layer "F.SilkS")
			(effects
				(font
					(size 0.65 0.65)
					(thickness 0.15)
				)
				(justify left bottom)
			)
		)
		(property "Value" "R_0R_0402"
			(at 0 1.4 0)
			(layer "F.Fab")
			(hide yes)
			(effects
				(font
					(size 0.7 0.7)
					(thickness 0.15)
				)
				(justify left bottom)
			)
		)
		(property "Datasheet" "https://industrial.panasonic.com/cdbs/www-data/pdf/RDA0000/AOA0000C301.pdf"
			(at 0 0 0)
			(layer "F.Fab")
			(hide yes)
			(effects
				(font
					(size 1.27 1.27)
					(thickness 0.15)
				)
			)
		)
		(property "Description" "SMD Chip Resistor, Jumper, 0 ohm, 100 mW, 0402 [1005 Metric], Thick Film, General Purpose"
			(at 0 0 0)
			(layer "F.Fab")
			(hide yes)
			(effects
				(font
					(size 1.27 1.27)
					(thickness 0.15)
				)
			)
		)
		(property "Author" "Antmicro"
			(at 0 0 0)
			(layer "F.Fab")
			(hide yes)
			(effects
				(font
					(size 1 1)
					(thickness 0.15)
				)
			)
		)
		(property "Current" "1A"
			(at 0 0 0)
			(layer "F.Fab")
			(hide yes)
			(effects
				(font
					(size 1 1)
					(thickness 0.15)
				)
			)
		)
		(property "License" "Apache-2.0"
			(at 0 0 0)
			(layer "F.Fab")
			(hide yes)
			(effects
				(font
					(size 1 1)
					(thickness 0.15)
				)
			)
		)
		(property "MPN" "ERJ2GE0R00X"
			(at 0 0 0)
			(layer "F.Fab")
			(hide yes)
			(effects
				(font
					(size 1 1)
					(thickness 0.15)
				)
			)
		)
		(property "Manufacturer" "Panasonic"
			(at 0 0 0)
			(layer "F.Fab")
			(hide yes)
			(effects
				(font
					(size 1 1)
					(thickness 0.15)
				)
			)
		)
		(property "Tolerance" "~"
			(at 0 0 0)
			(layer "F.Fab")
			(hide yes)
			(effects
				(font
					(size 1 1)
					(thickness 0.15)
				)
			)
		)
		(property "Val" "0R"
			(at 0 0 0)
			(layer "F.Fab")
			(hide yes)
			(effects
				(font
					(size 1 1)
					(thickness 0.15)
				)
			)
		)
		(sheetname "/FPGA/")
		(sheetfile "fpga.kicad_sch")
		(attr smd)
		(fp_rect
			(start -0.925 -0.47)
			(end 0.925 0.47)
			(stroke
				(width 0.05)
				(type default)
			)
			(fill no)
			(layer "F.CrtYd")
		)
		(fp_rect
			(start -0.5 -0.25)
			(end 0.5 0.25)
			(stroke
				(width 0.15)
				(type solid)
			)
			(fill no)
			(layer "F.Fab")
		)
		(fp_text user "Author: Antmicro"
			(at -0.95 4.169 0)
			(layer "F.Fab")
			(effects
				(font
					(size 0.7 0.7)
					(thickness 0.15)
				)
				(justify left bottom)
			)
		)
		(fp_text user "License: Apache-2.0"
			(at -0.95 5.169 0)
			(layer "F.Fab")
			(effects
				(font
					(size 0.7 0.7)
					(thickness 0.15)
				)
				(justify left bottom)
			)
		)
		(fp_text user "${REFERENCE}"
			(at -0.95 3.168 0)
			(layer "F.Fab")
			(effects
				(font
					(size 0.7 0.7)
					(thickness 0.15)
				)
				(justify left bottom)
			)
		)
		(pad "1" smd roundrect
			(at -0.48 0)
			(size 0.59 0.64)
			(layers "F.Cu" "F.Mask" "F.Paste")
			(roundrect_rratio 0.25)
			(net 330 "Net-(U17-A0)")
			(pintype "passive")
		)
		(pad "2" smd roundrect
			(at 0.48 0)
			(size 0.59 0.64)
			(layers "F.Cu" "F.Mask" "F.Paste")
			(roundrect_rratio 0.25)
			(net 1 "GND")
			(pintype "passive")
		)
	)
)
